FILE_TYPE = CONNECTIVITY;
{Allegro Design Entry HDL 17.4-2019 S026 (4007227) 1/17/2022}
"PAGE_NUMBER" = 175;
0"NC";
1"P5V_AUX\g";
2"P3V3_AUX\g";
3"GND\g";
4"GND\g";
5"GND\g";
6"GND\g";
7"GND\g";
8"GND\g";
9"GND\g";
10"P3V3_AUX\g";
11"GND\g";
12"GND\g";
13"GND\g";
14"GND\g";
15"GND\g";
16"GND\g";
17"GND\g";
18"GND\g";
19"GND\g";
20"GND\g";
21"GND\g";
22"GND\g";
23"VSENSE_PVDDCR_CPU1_P0_DP";
24"VSENSE_VSS_SENSE_C_P0";
25"GND\g";
26"PVDDCR_CPU1_P0\g";
27"NC_PVDDCR_CPU1_P0_IMON7";
28"PVDDCR_CPU1_P0_EN1_ADDR_CFG";
29"PWRGD_PVDDIO_P0_R";
30"PVDDCR_CPU1_P0_VMON";
31"VSENSE_VSS_SENSE_B_P0";
32"VSENSE_PVDDIO_P0_VSEN1";
33"PVDDIO_P0_EN_G";
34"P3V3_AUX\g";
35"PVDDIO_P0_EN_R";
36"SVID_PVDDCR_CPU1_P0_SVC_R";
37"SVID_PVDDCR_CPU1_P0_SVD_R";
38"PVDD18_S5_P0\g";
39"SVID_PVDDCR_CPU1_P0_SVTO";
40"PWRGD_PVDDCR_CPU1_P0";
41"FM_PVDDCR_CPU1_P0_EN";
42"PVDDCR_CPU1_P0_SMB_ALERT";
43"PWRGD_PVDDIO_P0";
44"PVDDIO_P0_EN";
45"PVDDCR_CPU1_P0_OCP_N";
46"SMB_SCM_2_R5_SDA";
47"PVDDCR_CPU1_P0_RESET_N";
48"SVID_PVDDCR_CPU1_P0_SVTI";
49"PVDDCR_CPU1_P0_IMON2";
50"PVDDCR_CPU1_P0_PWM2";
51"PVDDCR_CPU1_P0_IMON3";
52"PVDDCR_CPU1_P0_PWM3";
53"PVDDCR_CPU1_P0_IMON4";
54"PVDDCR_CPU1_P0_PWM4";
55"PVDDCR_CPU1_P0_IMON5";
56"PVDDCR_CPU1_P0_PWM5";
57"PVDDIO_P0_IMON1";
58"PVDDIO_P0_PWM1";
59"PVDDIO_P0_TEMP1";
60"PVDDCR_CPU1_P0_OCP_N_R";
61"PVDDIO_P0_IMON3";
62"PVDDCR_CPU1_P0_PWM1";
63"PVDDIO_P0_IMON2";
64"PVDDCR_CPU1_P0_TEMP0";
65"PVDDCR_CPU1_P0_VINSEN";
66"PVDDCR_CPU1_P0_VCCS";
67"PVDDCR_CPU1_P0_PWM6";
68"PWRGD_PVDDCR_CPU1_P0_R";
69"PVDDIO_P0_PWM2";
70"VSENSE_PVDDCR_CPU1_P0_VSEN0";
71"NC_PVDDCR_CPU1_P0_PWM7";
72"SMB_DIO_PVDDCR_CPU1_P0_R";
73"PVDDCR_CPU1_P0_EN_R";
74"PVDDCR_CPU1_P0_SMB_ALERT_R";
75"SVID_PVDDCR_CPU1_P0_SVD_R1";
76"NC_PVDDCR_CPU1_P0_IMON8";
77"PVDDCR_CPU1_P0_RESET_N_R";
78"SVID_PVDDCR_CPU1_P0_SVTO_R";
79"PVDDCR_CPU1_P0_IMON6";
80"SVID_PVDDCR_CPU1_P0_SVC_R1";
81"SMB_CLK_PVDDCR_CPU1_P0_R";
82"SVID_PVDDCR_CPU1_P0_SVTI_R";
83"PVDDCR_CPU1_P0_VCC";
84"SMB_SCM_2_R5_SCL";
85"PVDDCR_CPU1_P0_IMON1";
86"VSENSE_PVDDIO_P0_DP";
87"NC_PVDDCR_CPU1_P0_PWM8";
88"PVDDIO_P0_PWM4";
89"PVDDIO_P0_PWM3";
90"GND\g";
91"PVDD18_S5_P0\g";
92"GND\g";
93"P12V_AUX\g";
94"GND\g";
95"PVDD18_S5_P0\g";
96"GND\g";
97"PVDDIO_P0\g";
98"P3V3_AUX\g";
99"PVDDIO_P0_IMON4";
%"VCC_CORE"
"1","(-7325,1000)","0","pure_quanta_power","I10";
;
HDL_POWER"P5V_AUX"
CDS_LIB"pure_quanta_power";
"A"1;
%"Q_CAP"
"1","(-2750,6125)","0","pure_quanta","I100";
;
LOCATION"PC75"
$SEC"1"
CDS_SEC"1"
PACK_TYPE"C0402"
MATERIAL"X6S"
TOLERANCE"10%"
VALUE"1UF"
VOLTAGE"16V"
PART_NUMBER"CH5103KEB01"
CDS_LIB"pure_quanta";
"B"
$PN"2"22;
"A"
$PN"1"83;
%"VCC_CORE"
"1","(-6850,1300)","0","pure_quanta_power","I11";
;
HDL_POWER"P3V3_AUX"
CDS_LIB"pure_quanta_power";
"A"2;
%"UNIVERSAL_GND"
"1","(-2225,3025)","0","pure_quanta_power","I111";
;
HDL_POWER"GND"
CDS_LIB"pure_quanta_power";
"A"3;
%"UNIVERSAL_GND"
"1","(-2225,3325)","0","pure_quanta_power","I112";
;
HDL_POWER"GND"
CDS_LIB"pure_quanta_power";
"A"4;
%"Q_RES"
"2","(-6950,1600)","0","pure_quanta","I12";
;
LOCATION"PR67"
$SEC"1"
CDS_SEC"1"
VALUE"1.96K"
TOLERANCE"1%"
PACK_TYPE"0402LF"
MATERIAL"CHIP"
WATTAGE"1/16W"
PART_NUMBER"CS21962FB05"
CDS_LIB"pure_quanta";
"A"
$PN"1"28;
"B"
$PN"2"90;
%"Q_RES"
"1","(-2300,6300)","0","pure_quanta","I126";
;
LOCATION"PR76"
$SEC"1"
CDS_SEC"1"
PACK_TYPE"0402LF"
TOLERANCE"1%"
MATERIAL"CHIP"
VALUE"1"
WATTAGE"1/16W"
PART_NUMBER"CS-1002FB04"
CDS_LIB"pure_quanta";
"B"
$PN"2"98;
"A"
$PN"1"83;
%"VCC_CORE"
"1","(-1775,6425)","0","pure_quanta_power","I127";
;
HDL_POWER"P3V3_AUX"
CDS_LIB"pure_quanta_power";
"A"98;
%"RAA229620GNPHA0"
"1","(-4100,3550)","0","pure_quanta","I128";
;
LOCATION"PU12"
$SEC"1"
CDS_SEC"1"
PART_TYPE"SMLF"
VALUE"RAA229620GNP#HA0"
MATERIAL"IC"
PART_NUMBER"ARF0TGP4002"
CDS_LMAN_SYM_OUTLINE"-550,2850,500,-2850"
NEEDS_NO_SIZE"TRUE"
CDS_LIB"pure_quanta";
"CS10"
$PN"28"49;
"PWM10"
$PN"11"50;
"CS9"
$PN"29"51;
"PWM9"
$PN"10"52;
"CS8"
$PN"30"53;
"PWM8"
$PN"9"54;
"CS7"
$PN"31"55;
"PWM7"
$PN"8"56;
"CS0"
$PN"38"57;
"PWM0"
$PN"1"58;
"TEMP1"
$PN"43"59;
"EN1||ADDR_CFG"
$PN"42"28;
"TH_GND"
$PN"TH"92;
"OCP_L \B"
$PN"41"60;
"CS2"
$PN"36"61;
"PWM2"
$PN"3"89;
"CS3"
$PN"35"99;
"PWM3"
$PN"4"88;
"PWM11"
$PN"12"62;
"CS1"
$PN"37"63;
"RGND1"
$PN"39"31;
"VSEN1"
$PN"40"32;
"VDDIO"
$PN"19"38;
"TEMP0"
$PN"44"64;
"VINSEN"
$PN"46"65;
"VMON||IINSEN"
$PN"45"30;
"VCCS"
$PN"48"66;
"PWM6"
$PN"7"67;
"PG0"
$PN"16"68;
"PWM1"
$PN"2"69;
"VSEN0"
$PN"25"70;
"PWM5"
$PN"6"71;
"PWM4"
$PN"5"87;
"PMSDA"
$PN"13"72;
"RGND0"
$PN"26"24;
"EN0"
$PN"17"73;
"NPMALERT \B"
$PN"15"74;
"SVD"
$PN"21"75;
"PG1"
$PN"20"29;
"CS4"
$PN"34"76;
"CS5"
$PN"33"27;
"RESET_L \B"
$PN"18"77;
"SVTO"
$PN"23"78;
"CS6"
$PN"32"79;
"SVC"
$PN"22"80;
"PMSCL"
$PN"14"81;
"SVTI"
$PN"24"82;
"VCC"
$PN"47"83;
"CS11"
$PN"27"85;
%"Q_RES"
"2","(-8225,1400)","0","pure_quanta","I129";
;
LOCATION"R6086"
$SEC"1"
CDS_SEC"1"
VALUE"10K"
TOLERANCE"1%"
WATTAGE"1/16W"
MATERIAL"EMPTY"
PACK_TYPE"0402LF"
PART_NUMBER"CS31002FB08"
CDS_LIB"pure_quanta";
"A"
$PN"1"35;
"B"
$PN"2"96;
%"MOSFET_PCH_GDS_ESD_PROTECTED"
"1","(-6975,2075)","6","pure_quanta","I13";
;
LOCATION"PQ10"
$SEC"1"
CDS_SEC"1"
VALUE"PJA3415AE"
MATERIAL"IC"
PART_NUMBER"BAM34150008"
PART_TYPE"SMLF"
CDS_LIB"pure_quanta"
NEEDS_NO_SIZE"TRUE"
CDS_LMAN_SYM_OUTLINE"-125,150,125,-150";
"S"
$PN"S"34;
"G"
$PN"G"33;
"D"
$PN"D"28;
%"Q_CAP"
"1","(-6100,4675)","0","pure_quanta","I130";
;
LOCATION"C5013"
$SEC"1"
CDS_SEC"1"
VALUE"1000PF"
TOLERANCE"5%"
PACK_TYPE"0402"
VOLTAGE"50V"
MATERIAL"X7R"
PART_NUMBER"TMP_QCH21006JB10"
CDS_LIB"pure_quanta";
"B"
$PN"2"5;
"A"
$PN"1"42;
%"UNIVERSAL_GND"
"1","(-6100,4475)","0","pure_quanta_power","I131";
;
HDL_POWER"GND"
CDS_LIB"pure_quanta_power";
"A"5;
%"UNIVERSAL_GND"
"1","(-7575,1175)","7","pure_quanta_power","I132";
;
HDL_POWER"GND"
CDS_LIB"pure_quanta_power";
"A"6;
%"Q_CAP"
"2","(-7275,1175)","0","pure_quanta","I133";
;
LOCATION"C5005"
$SEC"1"
CDS_SEC"1"
VOLTAGE"50V"
TOLERANCE"5%"
PACK_TYPE"0402"
MATERIAL"X7R"
VALUE"1000PF"
PART_NUMBER"TMP_QCH21006JB10"
CDS_LIB"pure_quanta";
"A"
$PN"1"6;
"B"
$PN"2"43;
%"UNIVERSAL_GND"
"1","(-7550,6375)","7","pure_quanta_power","I134";
;
HDL_POWER"GND"
CDS_LIB"pure_quanta_power";
"A"7;
%"Q_CAP"
"2","(-7250,6375)","0","pure_quanta","I135";
;
LOCATION"C5004"
$SEC"1"
CDS_SEC"1"
TOLERANCE"5%"
PACK_TYPE"0402"
VOLTAGE"50V"
MATERIAL"X7R"
VALUE"1000PF"
PART_NUMBER"TMP_QCH21006JB10"
CDS_LIB"pure_quanta";
"A"
$PN"1"7;
"B"
$PN"2"40;
%"Q_RES"
"1","(-6500,5700)","0","pure_quanta","I136";
;
LOCATION"PR8008"
$SEC"1"
CDS_SEC"1"
PACK_TYPE"0402LF"
VALUE"0"
MATERIAL"CHIP"
WATTAGE"1/16W"
TOLERANCE"5%"
PART_NUMBER"CS00002JB13"
CDS_LIB"pure_quanta";
"B"
$PN"2"75;
"A"
$PN"1"37;
%"Q_RES"
"1","(-6475,5850)","0","pure_quanta","I137";
;
LOCATION"PR8007"
$SEC"1"
CDS_SEC"1"
PACK_TYPE"0402LF"
WATTAGE"1/16W"
VALUE"0"
MATERIAL"CHIP"
TOLERANCE"5%"
PART_NUMBER"CS00002JB13"
CDS_LIB"pure_quanta";
"B"
$PN"2"80;
"A"
$PN"1"36;
%"Q_RES"
"2","(-7600,2275)","0","pure_quanta","I17";
;
LOCATION"PR55"
$SEC"1"
CDS_SEC"1"
VALUE"1K"
PACK_TYPE"0402LF"
TOLERANCE"1%"
WATTAGE"1/16W"
MATERIAL"CHIP"
PART_NUMBER"CS21002FB06"
CDS_LIB"pure_quanta";
"A"
$PN"1"34;
"B"
$PN"2"33;
%"VCC_CORE"
"1","(-7600,2575)","0","pure_quanta_power","I18";
;
HDL_POWER"P3V3_AUX"
CDS_LIB"pure_quanta_power";
"A"34;
%"Q_RES"
"1","(-7150,2675)","0","pure_quanta","I19";
;
LOCATION"PR50"
$SEC"1"
CDS_SEC"1"
WATTAGE"1/16W"
PACK_TYPE"0402LF"
MATERIAL"CHIP"
VALUE"49.9"
TOLERANCE"1%"
PART_NUMBER"CS04992FB07"
CDS_LIB"pure_quanta";
"B"
$PN"2"8;
"A"
$PN"1"31;
%"Q_RES"
"1","(-8350,1650)","0","pure_quanta","I2";
;
LOCATION"R8047"
$SEC"1"
CDS_SEC"1"
TOLERANCE"5%"
VALUE"0"
MATERIAL"CHIP"
PACK_TYPE"0402LF"
WATTAGE"1/16W"
PART_NUMBER"CS00002JB13"
CDS_LIB"pure_quanta";
"B"
$PN"2"35;
"A"
$PN"1"44;
%"UNIVERSAL_GND"
"1","(-6625,2575)","0","pure_quanta_power","I21";
;
HDL_POWER"GND"
CDS_LIB"pure_quanta_power";
"A"8;
%"Q_RES"
"1","(-7100,3350)","0","pure_quanta","I22";
;
LOCATION"PR52"
$SEC"1"
CDS_SEC"1"
TOLERANCE"1%"
VALUE"49.9"
PACK_TYPE"0402LF"
MATERIAL"CHIP"
WATTAGE"1/16W"
PART_NUMBER"CS04992FB07"
CDS_LIB"pure_quanta";
"B"
$PN"2"97;
"A"
$PN"1"86;
%"Q_RES"
"1","(-7150,3775)","0","pure_quanta","I23";
;
LOCATION"PR49"
$SEC"1"
CDS_SEC"1"
TOLERANCE"1%"
PACK_TYPE"0402LF"
MATERIAL"CHIP"
WATTAGE"1/16W"
VALUE"49.9"
PART_NUMBER"CS04992FB07"
CDS_LIB"pure_quanta";
"B"
$PN"2"9;
"A"
$PN"1"24;
%"VCC_CORE"
"1","(-6600,3500)","0","pure_quanta_power","I24";
;
HDL_POWER"PVDDIO_P0"
CDS_LIB"pure_quanta_power";
"A"97;
%"UNIVERSAL_GND"
"1","(-6625,3675)","0","pure_quanta_power","I25";
;
HDL_POWER"GND"
CDS_LIB"pure_quanta_power";
"A"9;
%"UNIVERSAL_GND"
"1","(-8650,4750)","0","pure_quanta_power","I26";
;
HDL_POWER"GND"
CDS_LIB"pure_quanta_power";
"A"25;
%"Q_RES"
"2","(-8650,5200)","0","pure_quanta","I28";
;
LOCATION"PR40"
$SEC"1"
CDS_SEC"1"
WATTAGE"1/16W"
VALUE"0"
PACK_TYPE"0402LF"
MATERIAL"CHIP"
TOLERANCE"5%"
PART_NUMBER"CS00002JB13"
CDS_LIB"pure_quanta";
"A"
$PN"1"48;
"B"
$PN"2"25;
%"Q_CAP"
"1","(-8000,1425)","0","pure_quanta","I3";
;
LOCATION"C8066"
$SEC"1"
CDS_SEC"1"
VOLTAGE"50V"
TOLERANCE"5%"
VALUE"1000PF"
PACK_TYPE"0402"
MATERIAL"X7R"
PART_NUMBER"TMP_QCH21006JB10"
CDS_LIB"pure_quanta";
"B"
$PN"2"96;
"A"
$PN"1"35;
%"Q_RES"
"2","(-8425,5200)","0","pure_quanta","I32";
;
LOCATION"R8042"
$SEC"1"
CDS_SEC"1"
MATERIAL"EMPTY"
PACK_TYPE"0402LF"
TOLERANCE"1%"
WATTAGE"1/16W"
VALUE"1K"
PART_NUMBER"CS21002FB06"
CDS_LIB"pure_quanta";
"A"
$PN"1"39;
"B"
$PN"2"25;
%"Q_CAP"
"1","(-8250,5200)","0","pure_quanta","I33";
;
LOCATION"C303"
$SEC"1"
CDS_SEC"1"
VOLTAGE"50V"
MATERIAL"EMPTY"
VALUE"10PF"
PACK_TYPE"0402"
TOLERANCE"5%"
PART_NUMBER"CH01006JB08"
CDS_LIB"pure_quanta";
"B"
$PN"2"25;
"A"
$PN"1"39;
%"Q_CAP"
"1","(-8075,5200)","0","pure_quanta","I34";
;
LOCATION"C304"
$SEC"1"
CDS_SEC"1"
MATERIAL"EMPTY"
TOLERANCE"5%"
VALUE"10PF"
PACK_TYPE"0402"
VOLTAGE"50V"
PART_NUMBER"CH01006JB08"
CDS_LIB"pure_quanta";
"B"
$PN"2"25;
"A"
$PN"1"37;
%"Q_CAP"
"1","(-7825,5200)","0","pure_quanta","I35";
;
LOCATION"C305"
$SEC"1"
CDS_SEC"1"
TOLERANCE"5%"
MATERIAL"EMPTY"
VOLTAGE"50V"
PACK_TYPE"0402"
VALUE"10PF"
PART_NUMBER"CH01006JB08"
CDS_LIB"pure_quanta";
"B"
$PN"2"25;
"A"
$PN"1"36;
%"Q_RES"
"1","(-7100,4450)","0","pure_quanta","I36";
;
LOCATION"PR51"
$SEC"1"
CDS_SEC"1"
PACK_TYPE"0402LF"
TOLERANCE"1%"
VALUE"49.9"
MATERIAL"CHIP"
WATTAGE"1/16W"
PART_NUMBER"CS04992FB07"
CDS_LIB"pure_quanta";
"B"
$PN"2"26;
"A"
$PN"1"23;
%"UNIVERSAL_GND"
"1","(-8000,1175)","0","pure_quanta_power","I4";
;
HDL_POWER"GND"
CDS_LIB"pure_quanta_power";
"A"96;
%"Q_RES"
"2","(-8550,6175)","0","pure_quanta","I40";
;
LOCATION"PR41"
$SEC"1"
CDS_SEC"1"
MATERIAL"EMPTY"
WATTAGE"1/16W"
TOLERANCE"1%"
VALUE"1K"
PACK_TYPE"0402LF"
PART_NUMBER"CS21002FB06"
CDS_LIB"pure_quanta";
"A"
$PN"1"95;
"B"
$PN"2"48;
%"VCC_CORE"
"1","(-8550,6525)","0","pure_quanta_power","I41";
;
HDL_POWER"PVDD18_S5_P0"
CDS_LIB"pure_quanta_power";
"A"95;
%"Q_RES"
"2","(-8200,6175)","0","pure_quanta","I42";
;
LOCATION"R8043"
$SEC"1"
CDS_SEC"1"
TOLERANCE"1%"
WATTAGE"1/16W"
PACK_TYPE"0402LF"
MATERIAL"EMPTY"
VALUE"1K"
PART_NUMBER"CS21002FB06"
CDS_LIB"pure_quanta";
"A"
$PN"1"95;
"B"
$PN"2"39;
%"Q_RES"
"2","(-8000,6175)","0","pure_quanta","I43";
;
LOCATION"R8045"
$SEC"1"
CDS_SEC"1"
TOLERANCE"1%"
WATTAGE"1/16W"
MATERIAL"EMPTY"
VALUE"1K"
PACK_TYPE"0402LF"
PART_NUMBER"CS21002FB06"
CDS_LIB"pure_quanta";
"A"
$PN"1"95;
"B"
$PN"2"37;
%"Q_RES"
"2","(-7750,6175)","0","pure_quanta","I44";
;
LOCATION"R8048"
$SEC"1"
CDS_SEC"1"
MATERIAL"EMPTY"
PACK_TYPE"0402LF"
TOLERANCE"1%"
VALUE"1K"
WATTAGE"1/16W"
PART_NUMBER"CS21002FB06"
CDS_LIB"pure_quanta";
"A"
$PN"1"95;
"B"
$PN"2"36;
%"VCC_CORE"
"1","(-6900,6550)","0","pure_quanta_power","I47";
;
HDL_POWER"P3V3_AUX"
CDS_LIB"pure_quanta_power";
"A"10;
%"UNIVERSAL_GND"
"1","(-6200,475)","0","pure_quanta_power","I49";
;
HDL_POWER"GND"
CDS_LIB"pure_quanta_power";
"A"94;
%"Q_CAP"
"1","(-6200,800)","0","pure_quanta","I50";
;
LOCATION"PC67"
$SEC"1"
CDS_SEC"1"
VALUE"0.1UF"
VOLTAGE"25V"
PACK_TYPE"0402"
MATERIAL"X7R"
TOLERANCE"10%"
PART_NUMBER"CH4104K1B00"
CDS_LIB"pure_quanta";
"B"
$PN"2"94;
"A"
$PN"1"30;
%"Q_RES"
"1","(-5750,775)","0","pure_quanta","I51";
;
LOCATION"PR74"
$SEC"1"
CDS_SEC"1"
PACK_TYPE"0402LF"
VALUE"0"
TOLERANCE"5%"
MATERIAL"CHIP"
WATTAGE"1/16W"
PART_NUMBER"CS00002JB13"
CDS_LIB"pure_quanta";
"B"
$PN"2"65;
"A"
$PN"1"93;
%"VCC_CORE"
"1","(-5925,850)","0","pure_quanta_power","I52";
;
HDL_POWER"P12V_AUX"
CDS_LIB"pure_quanta_power";
"A"93;
%"Q_RES"
"1","(-6375,1050)","0","pure_quanta","I53";
;
LOCATION"R8066"
$SEC"1"
CDS_SEC"1"
WATTAGE"1/16W"
PACK_TYPE"0402LF"
TOLERANCE"5%"
MATERIAL"CHIP"
VALUE"33"
PART_NUMBER"CS03302JB10"
CDS_LIB"pure_quanta";
"B"
$PN"2"29;
"A"
$PN"1"43;
%"Q_RES"
"1","(-6375,1200)","0","pure_quanta","I54";
;
LOCATION"R8065"
$SEC"1"
CDS_SEC"1"
WATTAGE"1/16W"
PACK_TYPE"0402LF"
VALUE"1K"
TOLERANCE"1%"
MATERIAL"CHIP"
PART_NUMBER"CS21002FB06"
CDS_LIB"pure_quanta";
"B"
$PN"2"29;
"A"
$PN"1"2;
%"Q_CAP"
"2","(-5575,1200)","0","pure_quanta","I55";
;
LOCATION"C8072"
$SEC"1"
CDS_SEC"1"
PACK_TYPE"0402"
MATERIAL"EMPTY"
TOLERANCE"5%"
VOLTAGE"50V"
VALUE"1000PF"
PART_NUMBER"TMP_QCH21006JB10"
CDS_LIB"pure_quanta";
"A"
$PN"1"29;
"B"
$PN"2"14;
%"VCC_CORE"
"1","(-5975,2000)","0","pure_quanta_power","I56";
;
HDL_POWER"PVDD18_S5_P0"
CDS_LIB"pure_quanta_power";
"A"38;
%"UNIVERSAL_GND"
"1","(-5400,375)","0","pure_quanta_power","I57";
;
HDL_POWER"GND"
CDS_LIB"pure_quanta_power";
"A"11;
%"UNIVERSAL_GND"
"1","(-5075,375)","0","pure_quanta_power","I58";
;
HDL_POWER"GND"
CDS_LIB"pure_quanta_power";
"A"12;
%"Q_RES"
"2","(-5400,575)","0","pure_quanta","I59";
;
LOCATION"PR600"
$SEC"1"
CDS_SEC"1"
WATTAGE"1/16W"
PACK_TYPE"0402LF"
VALUE"4.99K"
TOLERANCE"1%"
MATERIAL"EMPTY"
PART_NUMBER"CS24992FB07"
CDS_LIB"pure_quanta";
"A"
$PN"1"65;
"B"
$PN"2"11;
%"MOSFET_N"
"1","(-7650,1750)","0","pure_quanta","I6";
;
LOCATION"PQ14"
$SEC"1"
CDS_SEC"1"
VALUE"BSS138K"
MATERIAL"IC"
PART_NUMBER"BAM138K0000"
MANUF_PN"BSS138K"
CDS_LIB"pure_quanta"
CDS_LMAN_SYM_OUTLINE"-50,50,100,-150"
PACK_TYPE"SMLF";
"GATE"
$PN"G"35;
"SOURCE"
$PN"S"90;
"DRAIN"
$PN"D"33;
%"Q_CAP"
"1","(-5075,575)","0","pure_quanta","I60";
;
LOCATION"PC74"
$SEC"1"
CDS_SEC"1"
TOLERANCE"10%"
MATERIAL"X7R"
VOLTAGE"25V"
VALUE"0.1UF"
PACK_TYPE"0402"
PART_NUMBER"CH4104K1B00"
CDS_LIB"pure_quanta";
"B"
$PN"2"12;
"A"
$PN"1"65;
%"UNIVERSAL_GND"
"1","(-4850,625)","0","pure_quanta_power","I61";
;
HDL_POWER"GND"
CDS_LIB"pure_quanta_power";
"A"92;
%"UNIVERSAL_GND"
"1","(-5025,1925)","1","pure_quanta_power","I62";
;
HDL_POWER"GND"
CDS_LIB"pure_quanta_power";
"A"13;
%"Q_CAP"
"2","(-5425,1925)","0","pure_quanta","I63";
;
LOCATION"PC73"
$SEC"1"
CDS_SEC"1"
VALUE"1UF"
TOLERANCE"10%"
PACK_TYPE"0402"
MATERIAL"X7R"
VOLTAGE"6.3V"
PART_NUMBER"CH5101K1B01"
CDS_LIB"pure_quanta";
"A"
$PN"1"38;
"B"
$PN"2"13;
%"UNIVERSAL_GND"
"1","(-4875,1200)","1","pure_quanta_power","I64";
;
HDL_POWER"GND"
CDS_LIB"pure_quanta_power";
"A"14;
%"VCC_CORE"
"1","(-6325,2725)","0","pure_quanta_power","I65";
;
HDL_POWER"PVDD18_S5_P0"
CDS_LIB"pure_quanta_power";
"A"91;
%"Q_RES"
"1","(-5725,2300)","0","pure_quanta","I66";
;
LOCATION"R8064"
$SEC"1"
CDS_SEC"1"
MATERIAL"CHIP"
VALUE"0"
TOLERANCE"5%"
PACK_TYPE"0402LF"
WATTAGE"1/16W"
PART_NUMBER"CS00002JB13"
CDS_LIB"pure_quanta";
"B"
$PN"2"60;
"A"
$PN"1"45;
%"Q_RES"
"1","(-5725,2450)","0","pure_quanta","I67";
;
LOCATION"R8063"
$SEC"1"
CDS_SEC"1"
VALUE"100"
WATTAGE"1/16W"
PACK_TYPE"0402LF"
TOLERANCE"1%"
MATERIAL"CHIP"
PART_NUMBER"CS11002FB07"
CDS_LIB"pure_quanta";
"B"
$PN"2"77;
"A"
$PN"1"47;
%"Q_RES"
"1","(-5875,2600)","0","pure_quanta","I68";
;
LOCATION"R8070"
$SEC"1"
CDS_SEC"1"
VALUE"1K"
TOLERANCE"1%"
WATTAGE"1/16W"
PACK_TYPE"0402LF"
MATERIAL"CHIP"
PART_NUMBER"CS21002FB06"
CDS_LIB"pure_quanta";
"B"
$PN"2"77;
"A"
$PN"1"91;
%"Q_CAP"
"1","(-5625,3025)","0","pure_quanta","I69";
;
LOCATION"PC71"
$SEC"1"
CDS_SEC"1"
MATERIAL"X7R"
PACK_TYPE"0402"
VOLTAGE"50V"
VALUE"3300PF"
TOLERANCE"10%"
PART_NUMBER"TMP_QCH2336K1B12"
CDS_LIB"pure_quanta";
"B"
$PN"2"31;
"A"
$PN"1"32;
%"UNIVERSAL_GND"
"1","(-7600,1375)","0","pure_quanta_power","I7";
;
HDL_POWER"GND"
CDS_LIB"pure_quanta_power";
"A"90;
%"Q_RES"
"1","(-6075,3200)","0","pure_quanta","I70";
;
LOCATION"PR69"
$SEC"1"
CDS_SEC"1"
PACK_TYPE"0402LF"
MATERIAL"CHIP"
WATTAGE"1/16W"
TOLERANCE"5%"
VALUE"0"
PART_NUMBER"CS00002JB13"
CDS_LIB"pure_quanta";
"B"
$PN"2"32;
"A"
$PN"1"86;
%"Q_RES"
"1","(-5175,2175)","0","pure_quanta","I71";
;
LOCATION"R8075"
$SEC"1"
CDS_SEC"1"
WATTAGE"1/16W"
PACK_TYPE"0402LF"
VALUE"1K"
TOLERANCE"1%"
MATERIAL"CHIP"
PART_NUMBER"CS21002FB06"
CDS_LIB"pure_quanta";
"B"
$PN"2"60;
"A"
$PN"1"38;
%"UNIVERSAL_GND"
"1","(-2750,675)","0","pure_quanta_power","I72";
;
HDL_POWER"GND"
CDS_LIB"pure_quanta_power";
"A"15;
%"Q_CAP"
"1","(-2750,925)","0","pure_quanta","I73";
;
LOCATION"PC78"
$SEC"1"
CDS_SEC"1"
MATERIAL"X7R"
TOLERANCE"10%"
VOLTAGE"50V"
PACK_TYPE"0402"
VALUE"470PF"
PART_NUMBER"TMP_QCH14706KB18"
CDS_LIB"pure_quanta";
"B"
$PN"2"15;
"A"
$PN"1"64;
%"UNIVERSAL_GND"
"1","(-2750,1250)","0","pure_quanta_power","I74";
;
HDL_POWER"GND"
CDS_LIB"pure_quanta_power";
"A"16;
%"Q_CAP"
"1","(-2750,1500)","0","pure_quanta","I75";
;
LOCATION"PC77"
$SEC"1"
CDS_SEC"1"
MATERIAL"X7R"
TOLERANCE"10%"
VALUE"470PF"
VOLTAGE"50V"
PACK_TYPE"0402"
PART_NUMBER"TMP_QCH14706KB18"
CDS_LIB"pure_quanta";
"B"
$PN"2"16;
"A"
$PN"1"59;
%"Q_RES"
"1","(-2675,3400)","0","pure_quanta","I76";
;
LOCATION"PR532"
$SEC"1"
CDS_SEC"1"
PACK_TYPE"0402LF"
VALUE"0"
TOLERANCE"5%"
WATTAGE"1/16W"
MATERIAL"CHIP"
PART_NUMBER"CS00002JB13"
CDS_LIB"pure_quanta";
"B"
$PN"2"4;
"A"
$PN"1"27;
%"Q_RES"
"1","(-2675,3100)","0","pure_quanta","I77";
;
LOCATION"PR32"
$SEC"1"
CDS_SEC"1"
PACK_TYPE"0402LF"
WATTAGE"1/16W"
VALUE"0"
TOLERANCE"5%"
MATERIAL"CHIP"
PART_NUMBER"CS00002JB13"
CDS_LIB"pure_quanta";
"B"
$PN"2"3;
"A"
$PN"1"76;
%"Q_RES"
"1","(-6125,4300)","0","pure_quanta","I78";
;
LOCATION"PR68"
$SEC"1"
CDS_SEC"1"
WATTAGE"1/16W"
MATERIAL"CHIP"
TOLERANCE"5%"
VALUE"0"
PACK_TYPE"0402LF"
PART_NUMBER"CS00002JB13"
CDS_LIB"pure_quanta";
"B"
$PN"2"70;
"A"
$PN"1"23;
%"VCC_CORE"
"1","(-6425,4600)","0","pure_quanta_power","I79";
;
HDL_POWER"PVDDCR_CPU1_P0"
CDS_LIB"pure_quanta_power";
"A"26;
%"Q_RES"
"2","(-6650,775)","0","pure_quanta","I8";
;
LOCATION"PR54"
$SEC"1"
CDS_SEC"1"
PACK_TYPE"0402LF"
VALUE"10K"
MATERIAL"CHIP"
WATTAGE"1/16W"
TOLERANCE"1%"
PART_NUMBER"CS31002FB08"
CDS_LIB"pure_quanta";
"A"
$PN"1"30;
"B"
$PN"2"94;
%"Q_CAP"
"1","(-5675,4125)","0","pure_quanta","I80";
;
LOCATION"PC68"
$SEC"1"
CDS_SEC"1"
VALUE"3300PF"
VOLTAGE"50V"
PACK_TYPE"0402"
MATERIAL"X7R"
TOLERANCE"10%"
PART_NUMBER"TMP_QCH2336K1B12"
CDS_LIB"pure_quanta";
"B"
$PN"2"24;
"A"
$PN"1"70;
%"Q_RES"
"1","(-5750,4850)","0","pure_quanta","I81";
;
LOCATION"R8073"
$SEC"1"
CDS_SEC"1"
MATERIAL"CHIP"
PACK_TYPE"0402LF"
WATTAGE"1/16W"
TOLERANCE"5%"
VALUE"33"
PART_NUMBER"CS03302JB10"
CDS_LIB"pure_quanta";
"B"
$PN"2"74;
"A"
$PN"1"42;
%"Q_RES"
"1","(-5750,5000)","0","pure_quanta","I82";
;
LOCATION"R8072"
$SEC"1"
CDS_SEC"1"
WATTAGE"1/16W"
MATERIAL"CHIP"
PACK_TYPE"0402LF"
VALUE"0"
TOLERANCE"5%"
PART_NUMBER"CS00002JB13"
CDS_LIB"pure_quanta";
"B"
$PN"2"72;
"A"
$PN"1"46;
%"Q_RES"
"1","(-6475,5550)","0","pure_quanta","I83";
;
LOCATION"R61"
$SEC"1"
CDS_SEC"1"
TOLERANCE"1%"
VALUE"49.9"
WATTAGE"1/16W"
MATERIAL"CHIP"
PACK_TYPE"0402LF"
PART_NUMBER"CS04992FB07"
CDS_LIB"pure_quanta";
"B"
$PN"2"78;
"A"
$PN"1"39;
%"Q_RES"
"1","(-6475,5400)","0","pure_quanta","I84";
;
LOCATION"PR62"
$SEC"1"
CDS_SEC"1"
PACK_TYPE"0402LF"
TOLERANCE"5%"
VALUE"0"
WATTAGE"1/16W"
MATERIAL"CHIP"
PART_NUMBER"CS00002JB13"
CDS_LIB"pure_quanta";
"B"
$PN"2"82;
"A"
$PN"1"48;
%"Q_RES"
"1","(-5750,5150)","0","pure_quanta","I85";
;
LOCATION"R8071"
$SEC"1"
CDS_SEC"1"
PACK_TYPE"0402LF"
MATERIAL"CHIP"
WATTAGE"1/16W"
VALUE"0"
TOLERANCE"5%"
PART_NUMBER"CS00002JB13"
CDS_LIB"pure_quanta";
"B"
$PN"2"81;
"A"
$PN"1"84;
%"Q_CAP"
"2","(-5650,6025)","0","pure_quanta","I86";
;
LOCATION"C8069"
$SEC"1"
CDS_SEC"1"
MATERIAL"X7R"
PACK_TYPE"0402"
TOLERANCE"5%"
VALUE"1000PF"
VOLTAGE"50V"
PART_NUMBER"TMP_QCH21006JB10"
CDS_LIB"pure_quanta";
"A"
$PN"1"73;
"B"
$PN"2"17;
%"UNIVERSAL_GND"
"1","(-4925,6025)","1","pure_quanta_power","I87";
;
HDL_POWER"GND"
CDS_LIB"pure_quanta_power";
"A"17;
%"Q_RES"
"1","(-6475,6150)","0","pure_quanta","I88";
;
LOCATION"R8058"
$SEC"1"
CDS_SEC"1"
PACK_TYPE"0402LF"
VALUE"0"
TOLERANCE"5%"
WATTAGE"1/16W"
MATERIAL"CHIP"
PART_NUMBER"CS00002JB13"
CDS_LIB"pure_quanta";
"B"
$PN"2"73;
"A"
$PN"1"41;
%"Q_RES"
"1","(-6475,6300)","0","pure_quanta","I89";
;
LOCATION"R8057"
$SEC"1"
CDS_SEC"1"
TOLERANCE"5%"
WATTAGE"1/16W"
PACK_TYPE"0402LF"
MATERIAL"CHIP"
VALUE"33"
PART_NUMBER"CS03302JB10"
CDS_LIB"pure_quanta";
"B"
$PN"2"68;
"A"
$PN"1"40;
%"Q_RES"
"1","(-6975,950)","0","pure_quanta","I9";
;
LOCATION"PR53"
$SEC"1"
CDS_SEC"1"
VALUE"40.2K"
MATERIAL"CHIP"
TOLERANCE"1%"
PACK_TYPE"0402LF"
PART_NUMBER"CS34022FB04"
CDS_LIB"pure_quanta"
WATTAGE"1/16W";
"B"
$PN"2"30;
"A"
$PN"1"1;
%"Q_RES"
"1","(-6475,6450)","0","pure_quanta","I90";
;
LOCATION"R8056"
$SEC"1"
CDS_SEC"1"
PACK_TYPE"0402LF"
VALUE"1K"
MATERIAL"CHIP"
WATTAGE"1/16W"
TOLERANCE"1%"
PART_NUMBER"CS21002FB06"
CDS_LIB"pure_quanta";
"B"
$PN"2"68;
"A"
$PN"1"10;
%"Q_CAP"
"2","(-5625,6450)","0","pure_quanta","I91";
;
LOCATION"C8070"
$SEC"1"
CDS_SEC"1"
TOLERANCE"5%"
VOLTAGE"50V"
VALUE"1000PF"
PACK_TYPE"0402"
MATERIAL"EMPTY"
PART_NUMBER"TMP_QCH21006JB10"
CDS_LIB"pure_quanta";
"A"
$PN"1"68;
"B"
$PN"2"18;
%"UNIVERSAL_GND"
"1","(-4925,6450)","1","pure_quanta_power","I92";
;
HDL_POWER"GND"
CDS_LIB"pure_quanta_power";
"A"18;
%"UNIVERSAL_GND"
"1","(-3075,5450)","0","pure_quanta_power","I93";
;
HDL_POWER"GND"
CDS_LIB"pure_quanta_power";
"A"19;
%"Q_CAP"
"1","(-3075,5675)","0","pure_quanta","I94";
;
LOCATION"PC15"
$SEC"1"
CDS_SEC"1"
VOLTAGE"25V"
TOLERANCE"10%"
MATERIAL"X7R"
PACK_TYPE"0402"
VALUE"0.1UF"
PART_NUMBER"CH4104K1B00"
CDS_LIB"pure_quanta";
"B"
$PN"2"19;
"A"
$PN"1"66;
%"UNIVERSAL_GND"
"1","(-3075,5925)","0","pure_quanta_power","I95";
;
HDL_POWER"GND"
CDS_LIB"pure_quanta_power";
"A"20;
%"Q_CAP"
"1","(-3075,6150)","0","pure_quanta","I96";
;
LOCATION"PC14"
$SEC"1"
CDS_SEC"1"
MATERIAL"X7R"
TOLERANCE"10%"
VALUE"0.1UF"
VOLTAGE"25V"
PACK_TYPE"0402"
PART_NUMBER"CH4104K1B00"
CDS_LIB"pure_quanta";
"B"
$PN"2"20;
"A"
$PN"1"83;
%"UNIVERSAL_GND"
"1","(-2750,5450)","0","pure_quanta_power","I97";
;
HDL_POWER"GND"
CDS_LIB"pure_quanta_power";
"A"21;
%"Q_CAP"
"1","(-2750,5650)","0","pure_quanta","I98";
;
LOCATION"PC76"
$SEC"1"
CDS_SEC"1"
TOLERANCE"20%"
PACK_TYPE"C0402"
VOLTAGE"6.3V"
VALUE"10UF"
MATERIAL"X6S"
PART_NUMBER"CH6101MEB03"
CDS_LIB"pure_quanta";
"B"
$PN"2"21;
"A"
$PN"1"66;
%"UNIVERSAL_GND"
"1","(-2750,5925)","0","pure_quanta_power","I99";
;
HDL_POWER"GND"
CDS_LIB"pure_quanta_power";
"A"22;
END.
